# BASEBOARD_FAB2 (Tioga Pass) — schematic netlist excerpt (pin names and nets, part order shuffled) for the footprints in the layout excerpt that follows; sources: Cadence DE-HDL packaged netlist, KiCad conversion of Wiwynn_Tioga_Pass_MB.brd

R2U31  RES  20.0 1% CHIP  pkg 0402  page 108 : A = SMB_SLOTX24_BMC_STBY_LVC3_SDA ; B = SMB_SLOTX24_STBY_LVC3_SDA_R2
C3P10  CAP  0.22UF 16V 10% X7R  pkg 0402  page 107 : A = P3E_CPU0_PE1_SS_TXP<0> ; B = P3E_CPU0_PE1_SS_C_TXP<0>

(kicad_pcb
	(version 20260206)
	(generator "pcbnew")
	(generator_version "10.0")
	(general
		(thickness 1.6)
		(legacy_teardrops no)
	)
	(paper "A4")
	(title_block
		(title "Wiwynn_Tioga_Pass_MB.brd")
		(comment 1 "Tioga Pass / footprints 3051-3052 of 4770")
	)
	(layers
		(0 "F.Cu" signal "TOP")
		(4 "In1.Cu" signal "L2GND")
		(6 "In2.Cu" signal "L3")
		(8 "In3.Cu" signal "L4GND")
		(10 "In4.Cu" signal "L5")
		(12 "In5.Cu" signal "L6GND")
		(14 "In6.Cu" signal "L7VCC")
		(16 "In7.Cu" signal "L8VCC")
		(18 "In8.Cu" signal "L9GND")
		(20 "In9.Cu" signal "L10")
		(22 "In10.Cu" signal "L11GND")
		(24 "In11.Cu" signal "L12")
		(26 "In12.Cu" signal "L13GND")
		(2 "B.Cu" signal "BOTTOM")
		(9 "F.Adhes" user "F.Adhesive")
		(11 "B.Adhes" user "B.Adhesive")
		(13 "F.Paste" user "Package Geometry/Pastemask Top")
		(15 "B.Paste" user "Package Geometry/Pastemask Bottom")
		(5 "F.SilkS" user "Ref Des/Silkscreen Top")
		(7 "B.SilkS" user "Ref Des/Silkscreen Bottom")
		(1 "F.Mask" user "Board Geometry/Soldermask Top")
		(3 "B.Mask" user "Board Geometry/Soldermask Bottom")
		(17 "Dwgs.User" user "User.Drawings")
		(19 "Cmts.User" user "User.Comments")
		(21 "Eco1.User" user "User.Eco1")
		(23 "Eco2.User" user "User.Eco2")
		(25 "Edge.Cuts" user "Board Geometry/Outline")
		(27 "Margin" user)
		(31 "F.CrtYd" user "Package Geometry/Place Bound Top")
		(29 "B.CrtYd" user "Package Geometry/Place Bound Bottom")
		(35 "F.Fab" user "Ref Des/Assembly Top")
		(33 "B.Fab" user "Ref Des/Assembly Bottom")
	)
	(footprint ""
		(layer "B.Cu")
		(at 469.197944 -11.42492)
		(property "Reference" "R2U31"
			(at 0 0 0)
			(layer "B.SilkS")
			(hide yes)
			(effects
				(font
					(size 1.27 1.27)
				)
				(justify mirror)
			)
		)
		(property "Value" ""
			(at 0 0 0)
			(layer "B.Fab")
			(effects
				(font
					(size 1.27 1.27)
				)
				(justify mirror)
			)
		)
		(duplicate_pad_numbers_are_jumpers no)
		(fp_poly
			(pts
				(xy 0.2794 -0.1016) (xy -0.2794 -0.1016) (xy -0.2794 0.9906) (xy 0.2794 0.9906)
			)
			(stroke
				(width 0)
				(type default)
			)
			(fill no)
			(layer "B.CrtYd")
		)
		(fp_line
			(start -0.2794 -0.1016)
			(end 0.2794 -0.1016)
			(stroke
				(width 0.1)
				(type default)
			)
			(layer "B.Fab")
		)
		(fp_line
			(start -0.2794 0.9906)
			(end -0.2794 -0.1016)
			(stroke
				(width 0.1)
				(type default)
			)
			(layer "B.Fab")
		)
		(fp_line
			(start 0.2794 -0.1016)
			(end 0.2794 0.9906)
			(stroke
				(width 0.1)
				(type default)
			)
			(layer "B.Fab")
		)
		(fp_line
			(start 0.2794 0.9906)
			(end -0.2794 0.9906)
			(stroke
				(width 0.1)
				(type default)
			)
			(layer "B.Fab")
		)
		(pad "1" smd rect
			(at 0 0 180)
			(size 0.508 0.508)
			(layers "B.Cu" "B.Mask" "B.Paste")
			(net "SMB_SLOTX24_BMC_STBY_LVC3_SDA")
		)
		(pad "2" smd rect
			(at 0 0.889 180)
			(size 0.508 0.508)
			(layers "B.Cu" "B.Mask" "B.Paste")
			(net "SMB_SLOTX24_STBY_LVC3_SDA_R2")
		)
		(zone
			(layer "B.Cu")
			(hatch none 0.5)
			(connect_pads
				(clearance 0)
			)
			(min_thickness 0.25)
			(keepout
				(tracks allowed)
				(vias not_allowed)
				(pads allowed)
				(copperpour not_allowed)
				(footprints allowed)
			)
			(placement
				(enabled no)
				(sheetname "")
			)
			(fill
				(thermal_gap 0.5)
				(thermal_bridge_width 0.5)
				(island_removal_mode 0)
			)
			(polygon
				(pts
					(xy 469.451944 -11.17092) (xy 468.943944 -11.17092) (xy 468.943944 -10.78992) (xy 469.451944 -10.78992)
				)
			)
		)
		(zone
			(layer "B.Cu")
			(hatch none 0.5)
			(connect_pads
				(clearance 0)
			)
			(min_thickness 0.25)
			(keepout
				(tracks not_allowed)
				(vias allowed)
				(pads allowed)
				(copperpour not_allowed)
				(footprints allowed)
			)
			(placement
				(enabled no)
				(sheetname "")
			)
			(fill
				(thermal_gap 0.5)
				(thermal_bridge_width 0.5)
				(island_removal_mode 0)
			)
			(polygon
				(pts
					(xy 469.451944 -10.78992) (xy 468.943944 -10.78992) (xy 468.943944 -11.17092) (xy 469.451944 -11.17092)
				)
			)
		)
	)
	(footprint ""
		(layer "B.Cu")
		(at 338.76996 -77.694536)
		(property "Reference" "C3P10"
			(at 0 0 0)
			(layer "B.SilkS")
			(hide yes)
			(effects
				(font
					(size 1.27 1.27)
				)
				(justify mirror)
			)
		)
		(property "Value" ""
			(at 0 0 0)
			(layer "B.Fab")
			(effects
				(font
					(size 1.27 1.27)
				)
				(justify mirror)
			)
		)
		(duplicate_pad_numbers_are_jumpers no)
		(fp_poly
			(pts
				(xy -0.3048 -0.1016) (xy -0.3048 0.9906) (xy 0.3048 0.9906) (xy 0.3048 -0.1016)
			)
			(stroke
				(width 0)
				(type default)
			)
			(fill no)
			(layer "B.CrtYd")
		)
		(fp_line
			(start -0.3048 -0.1016)
			(end 0.3048 -0.1016)
			(stroke
				(width 0.1)
				(type default)
			)
			(layer "B.Fab")
		)
		(fp_line
			(start -0.3048 0.9906)
			(end -0.3048 -0.1016)
			(stroke
				(width 0.1)
				(type default)
			)
			(layer "B.Fab")
		)
		(fp_line
			(start 0.3048 -0.1016)
			(end 0.3048 0.9906)
			(stroke
				(width 0.1)
				(type default)
			)
			(layer "B.Fab")
		)
		(fp_line
			(start 0.3048 0.9906)
			(end -0.3048 0.9906)
			(stroke
				(width 0.1)
				(type default)
			)
			(layer "B.Fab")
		)
		(pad "1" smd rect
			(at 0 0 180)
			(size 0.508 0.508)
			(layers "B.Cu" "B.Mask" "B.Paste")
			(net "P3E_CPU0_PE1_SS_TXP<0>")
		)
		(pad "2" smd rect
			(at 0 0.889 180)
			(size 0.508 0.508)
			(layers "B.Cu" "B.Mask" "B.Paste")
			(net "P3E_CPU0_PE1_SS_C_TXP<0>")
		)
		(zone
			(layer "B.Cu")
			(hatch none 0.5)
			(connect_pads
				(clearance 0)
			)
			(min_thickness 0.25)
			(keepout
				(tracks allowed)
				(vias not_allowed)
				(pads allowed)
				(copperpour not_allowed)
				(footprints allowed)
			)
			(placement
				(enabled no)
				(sheetname "")
			)
			(fill
				(thermal_gap 0.5)
				(thermal_bridge_width 0.5)
				(island_removal_mode 0)
			)
			(polygon
				(pts
					(xy 339.02396 -77.440536) (xy 338.51596 -77.440536) (xy 338.51596 -77.059536) (xy 339.02396 -77.059536)
				)
			)
		)
		(zone
			(layer "B.Cu")
			(hatch none 0.5)
			(connect_pads
				(clearance 0)
			)
			(min_thickness 0.25)
			(keepout
				(tracks not_allowed)
				(vias allowed)
				(pads allowed)
				(copperpour not_allowed)
				(footprints allowed)
			)
			(placement
				(enabled no)
				(sheetname "")
			)
			(fill
				(thermal_gap 0.5)
				(thermal_bridge_width 0.5)
				(island_removal_mode 0)
			)
			(polygon
				(pts
					(xy 339.02396 -77.059536) (xy 338.51596 -77.059536) (xy 338.51596 -77.440536) (xy 339.02396 -77.440536)
				)
			)
		)
	)
)
